(kicad_pcb
	(version 20241229)
	(generator "pcbnew")
	(generator_version "9.0")
	(general
		(thickness 1.599998)
		(legacy_teardrops no)
	)
	(paper "A4")
	(title_block
		(title "Artix - Datacenter Secure Control Module (DC-SCM)")
		(date "2024-11-06")
		(rev "1.1.3")
		(comment 9 "footprints 289-293 of 544")
	)
	(layers
		(0 "F.Cu" signal)
		(4 "In1.Cu" signal)
		(6 "In2.Cu" signal)
		(8 "In3.Cu" signal)
		(10 "In4.Cu" signal)
		(12 "In5.Cu" signal)
		(14 "In6.Cu" signal)
		(2 "B.Cu" signal)
		(9 "F.Adhes" user "F.Adhesive")
		(11 "B.Adhes" user "B.Adhesive")
		(13 "F.Paste" user)
		(15 "B.Paste" user)
		(5 "F.SilkS" user "F.Silkscreen")
		(7 "B.SilkS" user "B.Silkscreen")
		(1 "F.Mask" user)
		(3 "B.Mask" user)
		(17 "Dwgs.User" user "User.Drawings")
		(19 "Cmts.User" user "User.Comments")
		(21 "Eco1.User" user "User.Eco1")
		(23 "Eco2.User" user "User.Eco2")
		(25 "Edge.Cuts" user)
		(27 "Margin" user)
		(31 "F.CrtYd" user "F.Courtyard")
		(29 "B.CrtYd" user "B.Courtyard")
		(35 "F.Fab" user)
		(33 "B.Fab" user)
	)
	(footprint "antmicro-footprints:R_0402_1005Metric"
		(layer "B.Cu")
		(at 91.975 159.875 180)
		(descr "Resistor SMD 0402")
		(tags "resistor SMD 0402")
		(property "Reference" "R90"
			(at 0.775 -0.325 0)
			(layer "B.SilkS")
			(effects
				(font
					(size 0.7 0.7)
					(thickness 0.15)
				)
				(justify left bottom mirror)
			)
		)
		(property "Value" "R_4k7_0402"
			(at 0 -1.4 0)
			(layer "B.Fab")
			(effects
				(font
					(size 0.7 0.7)
					(thickness 0.15)
				)
				(justify left bottom mirror)
			)
		)
		(property "Datasheet" "https://www.bourns.com/docs/product-datasheets/cr.pdf"
			(at 0 0 180)
			(layer "F.Fab")
			(hide yes)
			(effects
				(font
					(size 1.27 1.27)
					(thickness 0.15)
				)
			)
		)
		(property "Description" "SMD Chip Resistor, 4.7 kohm, ± 1%, 62.5 mW, 0402 [1005 Metric], Thick Film, General Purpose"
			(at 0 0 180)
			(layer "F.Fab")
			(hide yes)
			(effects
				(font
					(size 1.27 1.27)
					(thickness 0.15)
				)
			)
		)
		(property "Author" "Antmicro"
			(at 183.95 319.75 0)
			(layer "B.Fab")
			(hide yes)
			(effects
				(font
					(size 1 1)
					(thickness 0.15)
				)
				(justify mirror)
			)
		)
		(property "License" "Apache-2.0"
			(at 183.95 319.75 0)
			(layer "B.Fab")
			(hide yes)
			(effects
				(font
					(size 1 1)
					(thickness 0.15)
				)
				(justify mirror)
			)
		)
		(property "MPN" "CR0402-FX-4701GLF"
			(at 183.95 319.75 0)
			(layer "B.Fab")
			(hide yes)
			(effects
				(font
					(size 1 1)
					(thickness 0.15)
				)
				(justify mirror)
			)
		)
		(property "Manufacturer" "Bourns"
			(at 183.95 319.75 0)
			(layer "B.Fab")
			(hide yes)
			(effects
				(font
					(size 1 1)
					(thickness 0.15)
				)
				(justify mirror)
			)
		)
		(property "Tolerance" "1%"
			(at 183.95 319.75 0)
			(layer "B.Fab")
			(hide yes)
			(effects
				(font
					(size 1 1)
					(thickness 0.15)
				)
				(justify mirror)
			)
		)
		(property "Val" "4k7"
			(at 183.95 319.75 0)
			(layer "B.Fab")
			(hide yes)
			(effects
				(font
					(size 1 1)
					(thickness 0.15)
				)
				(justify mirror)
			)
		)
		(sheetname "/FPGA banks 34-35 & CFG/")
		(sheetfile "fpga-banks-34-25-cfg.kicad_sch")
		(attr smd)
		(fp_rect
			(start -0.925 0.47)
			(end 0.925 -0.47)
			(stroke
				(width 0.05)
				(type default)
			)
			(fill no)
			(layer "B.CrtYd")
		)
		(fp_rect
			(start -0.5 0.25)
			(end 0.5 -0.25)
			(stroke
				(width 0.15)
				(type solid)
			)
			(fill no)
			(layer "B.Fab")
		)
		(pad "1" smd roundrect
			(at -0.48 0 180)
			(size 0.59 0.64)
			(layers "B.Cu" "B.Mask" "B.Paste")
			(roundrect_rratio 0.25)
			(net 2 "VCC3V3")
			(pintype "passive")
		)
		(pad "2" smd roundrect
			(at 0.48 0 180)
			(size 0.59 0.64)
			(layers "B.Cu" "B.Mask" "B.Paste")
			(roundrect_rratio 0.25)
			(net 222 "INIT")
			(pintype "passive")
		)
	)
	(footprint "antmicro-footprints:C_0402_1005Metric"
		(layer "B.Cu")
		(at 96.075 150.675 90)
		(descr "Capacitor SMD 0402")
		(tags "capacitor SMD 0402")
		(property "Reference" "C43"
			(at -2.925 0.425 90)
			(layer "B.SilkS")
			(effects
				(font
					(size 0.7 0.7)
					(thickness 0.15)
				)
				(justify right bottom mirror)
			)
		)
		(property "Value" "C_10u_0402"
			(at 0 -1.4 90)
			(layer "B.Fab")
			(effects
				(font
					(size 0.7 0.7)
					(thickness 0.15)
				)
				(justify right bottom mirror)
			)
		)
		(property "Datasheet" "https://www.yageo.com/en/Chart/Download/pdf/CC0402MRX5R5BB106"
			(at 0 0 90)
			(layer "F.Fab")
			(hide yes)
			(effects
				(font
					(size 1.27 1.27)
					(thickness 0.15)
				)
			)
		)
		(property "Description" "SMD Multilayer Ceramic Capacitor, 10 µF, 6.3 V, 0402 [1005 Metric], ± 20%, X5R, CC Series"
			(at 0 0 90)
			(layer "F.Fab")
			(hide yes)
			(effects
				(font
					(size 1.27 1.27)
					(thickness 0.15)
				)
			)
		)
		(property "Author" "Antmicro"
			(at 246.75 54.6 0)
			(layer "B.Fab")
			(hide yes)
			(effects
				(font
					(size 1 1)
					(thickness 0.15)
				)
				(justify mirror)
			)
		)
		(property "Dielectric" ""
			(at 246.75 54.6 0)
			(layer "B.Fab")
			(hide yes)
			(effects
				(font
					(size 1 1)
					(thickness 0.15)
				)
				(justify mirror)
			)
		)
		(property "License" "Apache-2.0"
			(at 246.75 54.6 0)
			(layer "B.Fab")
			(hide yes)
			(effects
				(font
					(size 1 1)
					(thickness 0.15)
				)
				(justify mirror)
			)
		)
		(property "MPN" "CC0402MRX5R5BB106"
			(at 246.75 54.6 0)
			(layer "B.Fab")
			(hide yes)
			(effects
				(font
					(size 1 1)
					(thickness 0.15)
				)
				(justify mirror)
			)
		)
		(property "Manufacturer" "YAGEO"
			(at 246.75 54.6 0)
			(layer "B.Fab")
			(hide yes)
			(effects
				(font
					(size 1 1)
					(thickness 0.15)
				)
				(justify mirror)
			)
		)
		(property "Val" "10u"
			(at 246.75 54.6 0)
			(layer "B.Fab")
			(hide yes)
			(effects
				(font
					(size 1 1)
					(thickness 0.15)
				)
				(justify mirror)
			)
		)
		(property "Voltage" ""
			(at 246.75 54.6 0)
			(layer "B.Fab")
			(hide yes)
			(effects
				(font
					(size 1 1)
					(thickness 0.15)
				)
				(justify mirror)
			)
		)
		(sheetname "/DDR3/")
		(sheetfile "ddr3.kicad_sch")
		(attr smd)
		(fp_rect
			(start -0.925 0.47)
			(end 0.925 -0.47)
			(stroke
				(width 0.05)
				(type default)
			)
			(fill no)
			(layer "B.CrtYd")
		)
		(fp_line
			(start 0.504 -0.248)
			(end -0.494 -0.248)
			(stroke
				(width 0.15)
				(type solid)
			)
			(layer "B.Fab")
		)
		(fp_line
			(start -0.494 -0.248)
			(end -0.494 0.25)
			(stroke
				(width 0.15)
				(type solid)
			)
			(layer "B.Fab")
		)
		(fp_line
			(start 0.504 0.25)
			(end 0.504 -0.248)
			(stroke
				(width 0.15)
				(type solid)
			)
			(layer "B.Fab")
		)
		(fp_line
			(start -0.494 0.25)
			(end 0.504 0.25)
			(stroke
				(width 0.15)
				(type solid)
			)
			(layer "B.Fab")
		)
		(pad "1" smd roundrect
			(at -0.48 0 90)
			(size 0.59 0.64)
			(layers "B.Cu" "B.Mask" "B.Paste")
			(roundrect_rratio 0.25)
			(net 1 "GND")
			(pintype "passive")
		)
		(pad "2" smd roundrect
			(at 0.48 0 90)
			(size 0.59 0.64)
			(layers "B.Cu" "B.Mask" "B.Paste")
			(roundrect_rratio 0.25)
			(net 143 "/DDR3/DDR3_VTT")
			(pintype "passive")
		)
	)
	(footprint "antmicro-footprints:C_1210_3225Metric"
		(layer "B.Cu")
		(at 88.7 133.6 90)
		(descr "Capacitor SMD 1210")
		(tags "capacitor SMD 1210")
		(property "Reference" "C91"
			(at 2.1 -1.2 180)
			(layer "B.SilkS")
			(effects
				(font
					(size 0.7 0.7)
					(thickness 0.15)
				)
				(justify right bottom mirror)
			)
		)
		(property "Value" "C_47u_1210"
			(at 0 -2.749 90)
			(layer "B.Fab")
			(effects
				(font
					(size 0.7 0.7)
					(thickness 0.15)
				)
				(justify right bottom mirror)
			)
		)
		(property "Datasheet" "https://www.kemet.com/en/us/capacitors/product/C1210C476K8RACTU.html"
			(at 0 0 90)
			(layer "F.Fab")
			(hide yes)
			(effects
				(font
					(size 1.27 1.27)
					(thickness 0.15)
				)
			)
		)
		(property "Description" "SMD Multilayer Ceramic Capacitor, 47 µF, 10 V, 1210 [3225 Metric], ± 10%, X7R, C Series KEMET"
			(at 0 0 90)
			(layer "F.Fab")
			(hide yes)
			(effects
				(font
					(size 1.27 1.27)
					(thickness 0.15)
				)
			)
		)
		(property "Author" "Antmicro"
			(at 222.3 44.9 0)
			(layer "B.Fab")
			(hide yes)
			(effects
				(font
					(size 1 1)
					(thickness 0.15)
				)
				(justify mirror)
			)
		)
		(property "Dielectric" ""
			(at 222.3 44.9 0)
			(layer "B.Fab")
			(hide yes)
			(effects
				(font
					(size 1 1)
					(thickness 0.15)
				)
				(justify mirror)
			)
		)
		(property "License" "Apache-2.0"
			(at 222.3 44.9 0)
			(layer "B.Fab")
			(hide yes)
			(effects
				(font
					(size 1 1)
					(thickness 0.15)
				)
				(justify mirror)
			)
		)
		(property "MPN" "C1210C476K8RACTU"
			(at 222.3 44.9 0)
			(layer "B.Fab")
			(hide yes)
			(effects
				(font
					(size 1 1)
					(thickness 0.15)
				)
				(justify mirror)
			)
		)
		(property "Manufacturer" "KEMET"
			(at 222.3 44.9 0)
			(layer "B.Fab")
			(hide yes)
			(effects
				(font
					(size 1 1)
					(thickness 0.15)
				)
				(justify mirror)
			)
		)
		(property "Public" "False"
			(at 222.3 44.9 0)
			(layer "B.Fab")
			(hide yes)
			(effects
				(font
					(size 1 1)
					(thickness 0.15)
				)
				(justify mirror)
			)
		)
		(property "Val" "47u"
			(at 222.3 44.9 0)
			(layer "B.Fab")
			(hide yes)
			(effects
				(font
					(size 1 1)
					(thickness 0.15)
				)
				(justify mirror)
			)
		)
		(property "Voltage" ""
			(at 222.3 44.9 0)
			(layer "B.Fab")
			(hide yes)
			(effects
				(font
					(size 1 1)
					(thickness 0.15)
				)
				(justify mirror)
			)
		)
		(sheetname "/FPGA banks 34-35 & CFG/")
		(sheetfile "fpga-banks-34-25-cfg.kicad_sch")
		(attr smd)
		(fp_line
			(start -0.3 -1.39)
			(end 0.3 -1.39)
			(stroke
				(width 0.15)
				(type solid)
			)
			(layer "B.SilkS")
		)
		(fp_line
			(start -0.3 1.39)
			(end 0.3 1.39)
			(stroke
				(width 0.15)
				(type solid)
			)
			(layer "B.SilkS")
		)
		(fp_rect
			(start -2.1 1.75)
			(end 2.1 -1.75)
			(stroke
				(width 0.05)
				(type solid)
			)
			(fill no)
			(layer "B.CrtYd")
		)
		(fp_rect
			(start -1.6 1.25)
			(end 1.6 -1.25)
			(stroke
				(width 0.15)
				(type solid)
			)
			(fill no)
			(layer "B.Fab")
		)
		(pad "1" smd rect
			(at -1.145 0 90)
			(size 1.52 3.05)
			(layers "B.Cu" "B.Mask" "B.Paste")
			(net 1 "GND")
			(pintype "passive")
		)
		(pad "2" smd rect
			(at 1.145 0 90)
			(size 1.52 3.05)
			(layers "B.Cu" "B.Mask" "B.Paste")
			(net 2 "VCC3V3")
			(pintype "passive")
		)
	)
	(footprint "antmicro-footprints:C_1210_3225Metric"
		(layer "B.Cu")
		(at 114.4 134.1 180)
		(descr "Capacitor SMD 1210")
		(tags "capacitor SMD 1210")
		(property "Reference" "C94"
			(at 2.2 1.1 270)
			(layer "B.SilkS")
			(effects
				(font
					(size 0.7 0.7)
					(thickness 0.15)
				)
				(justify left bottom mirror)
			)
		)
		(property "Value" "C_47u_1210"
			(at 0 -2.749 0)
			(layer "B.Fab")
			(effects
				(font
					(size 0.7 0.7)
					(thickness 0.15)
				)
				(justify left bottom mirror)
			)
		)
		(property "Datasheet" "https://www.kemet.com/en/us/capacitors/product/C1210C476K8RACTU.html"
			(at 0 0 180)
			(layer "F.Fab")
			(hide yes)
			(effects
				(font
					(size 1.27 1.27)
					(thickness 0.15)
				)
			)
		)
		(property "Description" "SMD Multilayer Ceramic Capacitor, 47 µF, 10 V, 1210 [3225 Metric], ± 10%, X7R, C Series KEMET"
			(at 0 0 180)
			(layer "F.Fab")
			(hide yes)
			(effects
				(font
					(size 1.27 1.27)
					(thickness 0.15)
				)
			)
		)
		(property "Author" "Antmicro"
			(at 228.8 268.2 0)
			(layer "B.Fab")
			(hide yes)
			(effects
				(font
					(size 1 1)
					(thickness 0.15)
				)
				(justify mirror)
			)
		)
		(property "Dielectric" ""
			(at 228.8 268.2 0)
			(layer "B.Fab")
			(hide yes)
			(effects
				(font
					(size 1 1)
					(thickness 0.15)
				)
				(justify mirror)
			)
		)
		(property "License" "Apache-2.0"
			(at 228.8 268.2 0)
			(layer "B.Fab")
			(hide yes)
			(effects
				(font
					(size 1 1)
					(thickness 0.15)
				)
				(justify mirror)
			)
		)
		(property "MPN" "C1210C476K8RACTU"
			(at 228.8 268.2 0)
			(layer "B.Fab")
			(hide yes)
			(effects
				(font
					(size 1 1)
					(thickness 0.15)
				)
				(justify mirror)
			)
		)
		(property "Manufacturer" "KEMET"
			(at 228.8 268.2 0)
			(layer "B.Fab")
			(hide yes)
			(effects
				(font
					(size 1 1)
					(thickness 0.15)
				)
				(justify mirror)
			)
		)
		(property "Public" "False"
			(at 228.8 268.2 0)
			(layer "B.Fab")
			(hide yes)
			(effects
				(font
					(size 1 1)
					(thickness 0.15)
				)
				(justify mirror)
			)
		)
		(property "Val" "47u"
			(at 228.8 268.2 0)
			(layer "B.Fab")
			(hide yes)
			(effects
				(font
					(size 1 1)
					(thickness 0.15)
				)
				(justify mirror)
			)
		)
		(property "Voltage" ""
			(at 228.8 268.2 0)
			(layer "B.Fab")
			(hide yes)
			(effects
				(font
					(size 1 1)
					(thickness 0.15)
				)
				(justify mirror)
			)
		)
		(sheetname "/FPGA banks 13-16/")
		(sheetfile "fpga-banks-13-16.kicad_sch")
		(attr smd)
		(fp_line
			(start -0.3 1.39)
			(end 0.3 1.39)
			(stroke
				(width 0.15)
				(type solid)
			)
			(layer "B.SilkS")
		)
		(fp_line
			(start -0.3 -1.39)
			(end 0.3 -1.39)
			(stroke
				(width 0.15)
				(type solid)
			)
			(layer "B.SilkS")
		)
		(fp_rect
			(start -2.1 1.75)
			(end 2.1 -1.75)
			(stroke
				(width 0.05)
				(type solid)
			)
			(fill no)
			(layer "B.CrtYd")
		)
		(fp_rect
			(start -1.6 1.25)
			(end 1.6 -1.25)
			(stroke
				(width 0.15)
				(type solid)
			)
			(fill no)
			(layer "B.Fab")
		)
		(pad "1" smd rect
			(at -1.145 0 180)
			(size 1.52 3.05)
			(layers "B.Cu" "B.Mask" "B.Paste")
			(net 1 "GND")
			(pintype "passive")
		)
		(pad "2" smd rect
			(at 1.145 0 180)
			(size 1.52 3.05)
			(layers "B.Cu" "B.Mask" "B.Paste")
			(net 2 "VCC3V3")
			(pintype "passive")
		)
	)
	(footprint "antmicro-footprints:C_0603_1608Metric"
		(layer "B.Cu")
		(at 93.6 119.1)
		(descr "Capacitor SMD 0603")
		(tags "capacitor 0603")
		(property "Reference" "C156"
			(at -1.6 -1.8 0)
			(layer "B.SilkS")
			(effects
				(font
					(size 0.7 0.7)
					(thickness 0.15)
				)
				(justify right bottom mirror)
			)
		)
		(property "Value" "C_4u7_0603"
			(at 0 -1.6 0)
			(layer "B.Fab")
			(effects
				(font
					(size 0.7 0.7)
					(thickness 0.15)
				)
				(justify right bottom mirror)
			)
		)
		(property "Datasheet" "https://product.tdk.com/en/search/capacitor/ceramic/mlcc/info?part_no=C1608X5R1V475M080AC"
			(at 0 0 0)
			(layer "F.Fab")
			(hide yes)
			(effects
				(font
					(size 1.27 1.27)
					(thickness 0.15)
				)
			)
		)
		(property "Description" "SMD Multilayer Ceramic Capacitor, 4.7 µF, 35 V, 0603 [1608 Metric], ± 20%, X5R, C"
			(at 0 0 0)
			(layer "F.Fab")
			(hide yes)
			(effects
				(font
					(size 1.27 1.27)
					(thickness 0.15)
				)
			)
		)
		(property "Author" "Antmicro"
			(at 0 0 0)
			(layer "B.Fab")
			(hide yes)
			(effects
				(font
					(size 1 1)
					(thickness 0.15)
				)
				(justify mirror)
			)
		)
		(property "Dielectric" ""
			(at 0 0 0)
			(layer "B.Fab")
			(hide yes)
			(effects
				(font
					(size 1 1)
					(thickness 0.15)
				)
				(justify mirror)
			)
		)
		(property "License" "Apache-2.0"
			(at 0 0 0)
			(layer "B.Fab")
			(hide yes)
			(effects
				(font
					(size 1 1)
					(thickness 0.15)
				)
				(justify mirror)
			)
		)
		(property "MPN" "C1608X5R1V475M080AC"
			(at 0 0 0)
			(layer "B.Fab")
			(hide yes)
			(effects
				(font
					(size 1 1)
					(thickness 0.15)
				)
				(justify mirror)
			)
		)
		(property "Manufacturer" "TDK"
			(at 0 0 0)
			(layer "B.Fab")
			(hide yes)
			(effects
				(font
					(size 1 1)
					(thickness 0.15)
				)
				(justify mirror)
			)
		)
		(property "Val" "4u7"
			(at 0 0 0)
			(layer "B.Fab")
			(hide yes)
			(effects
				(font
					(size 1 1)
					(thickness 0.15)
				)
				(justify mirror)
			)
		)
		(property "Voltage" ""
			(at 0 0 0)
			(layer "B.Fab")
			(hide yes)
			(effects
				(font
					(size 1 1)
					(thickness 0.15)
				)
				(justify mirror)
			)
		)
		(property "DNP" ""
			(at 0 0 0)
			(unlocked yes)
			(layer "B.Fab")
			(hide yes)
			(effects
				(font
					(size 1 1)
					(thickness 0.15)
				)
				(justify mirror)
			)
		)
		(sheetname "/FPGA power supply/")
		(sheetfile "fpga-power-supply.kicad_sch")
		(attr smd)
		(fp_line
			(start -0.15 -0.4)
			(end 0.15 -0.4)
			(stroke
				(width 0.15)
				(type solid)
			)
			(layer "B.SilkS")
		)
		(fp_line
			(start -0.15 0.4)
			(end 0.15 0.4)
			(stroke
				(width 0.15)
				(type solid)
			)
			(layer "B.SilkS")
		)
		(fp_rect
			(start -1.25 0.65)
			(end 1.25 -0.65)
			(stroke
				(width 0.05)
				(type solid)
			)
			(fill no)
			(layer "B.CrtYd")
		)
		(fp_rect
			(start -0.8 0.4)
			(end 0.8 -0.4)
			(stroke
				(width 0.15)
				(type solid)
			)
			(fill no)
			(layer "B.Fab")
		)
		(pad "1" smd roundrect
			(at -0.7 0)
			(size 0.8 1)
			(layers "B.Cu" "B.Mask" "B.Paste")
			(roundrect_rratio 0.2)
			(net 1 "GND")
			(pintype "passive")
		)
		(pad "2" smd roundrect
			(at 0.7 0)
			(size 0.8 1)
			(layers "B.Cu" "B.Mask" "B.Paste")
			(roundrect_rratio 0.2)
			(net 6 "VCC1V0")
			(pintype "passive")
		)
	)
)
